# T6G (Grand Teton) — schematic netlist excerpt (pin names and nets, part order shuffled) for the footprints in the layout excerpt that follows; sources: Cadence DE-HDL packaged netlist, KiCad conversion of 04192023_DAF0TMB3IC0_F0TG_MB_C_brd_V02_OCP.brd

PC2137  Q_CAP  0.1UF 25V 10% X7R  pkg 0402  page 140 : A = P3V3_OCP_V3_2_R ; B = GND
R2316  Q_RES  0 5% CHIP  pkg 0402LF  page 189 : A = PWRGD_P5V_AUX_R ; B = PWRGD_P5V_AUX

(kicad_pcb
	(version 20260206)
	(generator "pcbnew")
	(generator_version "10.0")
	(general
		(thickness 1.6)
		(legacy_teardrops no)
	)
	(paper "A4")
	(title_block
		(title "04192023_DAF0TMB3IC0_F0TG_MB_C_brd_V02_OCP.brd")
		(comment 1 "Grand Teton / footprints 4660-4661 of 8354")
	)
	(layers
		(0 "F.Cu" signal "TOP")
		(4 "In1.Cu" signal "GND")
		(6 "In2.Cu" signal "IN1")
		(8 "In3.Cu" signal "GND1")
		(10 "In4.Cu" signal "IN2")
		(12 "In5.Cu" signal "GND2")
		(14 "In6.Cu" signal "IN3")
		(16 "In7.Cu" signal "GND3")
		(18 "In8.Cu" signal "VCC")
		(20 "In9.Cu" signal "VCC1")
		(22 "In10.Cu" signal "GND4")
		(24 "In11.Cu" signal "IN4")
		(26 "In12.Cu" signal "GND5")
		(28 "In13.Cu" signal "IN5")
		(30 "In14.Cu" signal "GND6")
		(32 "In15.Cu" signal "IN6")
		(34 "In16.Cu" signal "GND7")
		(2 "B.Cu" signal "BOTTOM")
		(9 "F.Adhes" user "F.Adhesive")
		(11 "B.Adhes" user "B.Adhesive")
		(13 "F.Paste" user "Package Geometry/Pastemask Top")
		(15 "B.Paste" user "Package Geometry/Pastemask Bottom")
		(5 "F.SilkS" user "Ref Des/Silkscreen Top")
		(7 "B.SilkS" user "Ref Des/Silkscreen Bottom")
		(1 "F.Mask" user "Board Geometry/Soldermask Top")
		(3 "B.Mask" user "Board Geometry/Soldermask Bottom")
		(17 "Dwgs.User" user "User.Drawings")
		(19 "Cmts.User" user "User.Comments")
		(21 "Eco1.User" user "User.Eco1")
		(23 "Eco2.User" user "User.Eco2")
		(25 "Edge.Cuts" user "Board Geometry/Outline")
		(27 "Margin" user)
		(31 "F.CrtYd" user "Package Geometry/Place Bound Top")
		(29 "B.CrtYd" user "Package Geometry/Place Bound Bottom")
		(35 "F.Fab" user "Ref Des/Assembly Top")
		(33 "B.Fab" user "Ref Des/Assembly Bottom")
	)
	(footprint ""
		(layer "F.Cu")
		(at 409.46451 -136.835642 180)
		(property "Reference" "R2316"
			(at 0 0 180)
			(layer "F.SilkS")
			(hide yes)
			(effects
				(font
					(size 1.27 1.27)
				)
			)
		)
		(property "Value" ""
			(at 0 0 180)
			(layer "F.Fab")
			(effects
				(font
					(size 1.27 1.27)
				)
			)
		)
		(duplicate_pad_numbers_are_jumpers no)
		(fp_line
			(start 0.7874 0.4064)
			(end -0.7874 0.4064)
			(stroke
				(width 0.1524)
				(type default)
			)
			(layer "F.SilkS")
		)
		(fp_line
			(start 0.7874 -0.4064)
			(end 0.7874 0.4064)
			(stroke
				(width 0.1524)
				(type default)
			)
			(layer "F.SilkS")
		)
		(fp_line
			(start -0.7874 0.4064)
			(end -0.7874 -0.4064)
			(stroke
				(width 0.1524)
				(type default)
			)
			(layer "F.SilkS")
		)
		(fp_line
			(start -0.7874 -0.4064)
			(end 0.7874 -0.4064)
			(stroke
				(width 0.1524)
				(type default)
			)
			(layer "F.SilkS")
		)
		(fp_line
			(start 0.67945 0.3048)
			(end 0.120396 0.3048)
			(stroke
				(width 0.1)
				(type default)
			)
			(layer "F.Fab")
		)
		(fp_line
			(start 0.67945 -0.3048)
			(end 0.67945 0.3048)
			(stroke
				(width 0.1)
				(type default)
			)
			(layer "F.Fab")
		)
		(fp_line
			(start 0.12065 -0.2794)
			(end 0.12065 -0.3048)
			(stroke
				(width 0.1)
				(type default)
			)
			(layer "F.Fab")
		)
		(fp_line
			(start 0.12065 -0.3048)
			(end 0.67945 -0.3048)
			(stroke
				(width 0.1)
				(type default)
			)
			(layer "F.Fab")
		)
		(fp_line
			(start 0.120396 0.3048)
			(end 0.120396 0.2794)
			(stroke
				(width 0.1)
				(type default)
			)
			(layer "F.Fab")
		)
		(fp_line
			(start 0.120396 0.2794)
			(end -0.12065 0.2794)
			(stroke
				(width 0.1)
				(type default)
			)
			(layer "F.Fab")
		)
		(fp_line
			(start -0.12065 0.3048)
			(end -0.67945 0.3048)
			(stroke
				(width 0.1)
				(type default)
			)
			(layer "F.Fab")
		)
		(fp_line
			(start -0.12065 0.2794)
			(end -0.12065 0.3048)
			(stroke
				(width 0.1)
				(type default)
			)
			(layer "F.Fab")
		)
		(fp_line
			(start -0.12065 -0.2794)
			(end 0.12065 -0.2794)
			(stroke
				(width 0.1)
				(type default)
			)
			(layer "F.Fab")
		)
		(fp_line
			(start -0.12065 -0.305054)
			(end -0.12065 -0.2794)
			(stroke
				(width 0.1)
				(type default)
			)
			(layer "F.Fab")
		)
		(fp_line
			(start -0.67945 0.3048)
			(end -0.67945 -0.305054)
			(stroke
				(width 0.1)
				(type default)
			)
			(layer "F.Fab")
		)
		(fp_line
			(start -0.67945 -0.305054)
			(end -0.12065 -0.305054)
			(stroke
				(width 0.1)
				(type default)
			)
			(layer "F.Fab")
		)
		(pad "1" smd circle
			(at -0.40005 0 180)
			(size 0 0)
			(layers "F.Cu" "F.Mask" "F.Paste")
			(net "PWRGD_P5V_AUX_R")
		)
		(pad "2" smd circle
			(at 0.40005 0 180)
			(size 0 0)
			(layers "F.Cu" "F.Mask" "F.Paste")
			(net "PWRGD_P5V_AUX")
		)
	)
	(footprint ""
		(layer "F.Cu")
		(at 94.338648 -69.488558 90)
		(property "Reference" "PC2137"
			(at 0 0 90)
			(layer "F.SilkS")
			(hide yes)
			(effects
				(font
					(size 1.27 1.27)
				)
			)
		)
		(property "Value" ""
			(at 0 0 90)
			(layer "F.Fab")
			(effects
				(font
					(size 1.27 1.27)
				)
			)
		)
		(duplicate_pad_numbers_are_jumpers no)
		(fp_line
			(start 0.7874 -0.4064)
			(end 0.7874 0.4064)
			(stroke
				(width 0.1524)
				(type default)
			)
			(layer "F.SilkS")
		)
		(fp_line
			(start -0.7874 -0.4064)
			(end 0.7874 -0.4064)
			(stroke
				(width 0.1524)
				(type default)
			)
			(layer "F.SilkS")
		)
		(fp_line
			(start 0.7874 0.4064)
			(end -0.7874 0.4064)
			(stroke
				(width 0.1524)
				(type default)
			)
			(layer "F.SilkS")
		)
		(fp_line
			(start -0.7874 0.4064)
			(end -0.7874 -0.4064)
			(stroke
				(width 0.1524)
				(type default)
			)
			(layer "F.SilkS")
		)
		(fp_line
			(start -0.12065 -0.305054)
			(end -0.12065 -0.2794)
			(stroke
				(width 0.1)
				(type default)
			)
			(layer "F.Fab")
		)
		(fp_line
			(start -0.67945 -0.305054)
			(end -0.12065 -0.305054)
			(stroke
				(width 0.1)
				(type default)
			)
			(layer "F.Fab")
		)
		(fp_line
			(start 0.67945 -0.3048)
			(end 0.67945 0.3048)
			(stroke
				(width 0.1)
				(type default)
			)
			(layer "F.Fab")
		)
		(fp_line
			(start 0.12065 -0.3048)
			(end 0.67945 -0.3048)
			(stroke
				(width 0.1)
				(type default)
			)
			(layer "F.Fab")
		)
		(fp_line
			(start 0.12065 -0.2794)
			(end 0.12065 -0.3048)
			(stroke
				(width 0.1)
				(type default)
			)
			(layer "F.Fab")
		)
		(fp_line
			(start -0.12065 -0.2794)
			(end 0.12065 -0.2794)
			(stroke
				(width 0.1)
				(type default)
			)
			(layer "F.Fab")
		)
		(fp_line
			(start 0.120396 0.2794)
			(end -0.12065 0.2794)
			(stroke
				(width 0.1)
				(type default)
			)
			(layer "F.Fab")
		)
		(fp_line
			(start -0.12065 0.2794)
			(end -0.12065 0.3048)
			(stroke
				(width 0.1)
				(type default)
			)
			(layer "F.Fab")
		)
		(fp_line
			(start 0.67945 0.3048)
			(end 0.120396 0.3048)
			(stroke
				(width 0.1)
				(type default)
			)
			(layer "F.Fab")
		)
		(fp_line
			(start 0.120396 0.3048)
			(end 0.120396 0.2794)
			(stroke
				(width 0.1)
				(type default)
			)
			(layer "F.Fab")
		)
		(fp_line
			(start -0.12065 0.3048)
			(end -0.67945 0.3048)
			(stroke
				(width 0.1)
				(type default)
			)
			(layer "F.Fab")
		)
		(fp_line
			(start -0.67945 0.3048)
			(end -0.67945 -0.305054)
			(stroke
				(width 0.1)
				(type default)
			)
			(layer "F.Fab")
		)
		(pad "1" smd circle
			(at -0.40005 0 90)
			(size 0 0)
			(layers "F.Cu" "F.Mask" "F.Paste")
			(net "P3V3_OCP_V3_2_R")
		)
		(pad "2" smd circle
			(at 0.40005 0 90)
			(size 0 0)
			(layers "F.Cu" "F.Mask" "F.Paste")
			(net "GND")
		)
	)
)
